(kicad_pcb
	(version 20260206)
	(generator "pcbnew")
	(generator_version "10.0")
	(general
		(thickness 1.6)
		(legacy_teardrops no)
	)
	(paper "A4")
	(title_block
		(title "pdpb — Lightning_PDPB_BRD.brd")
		(comment 1 "Lightning (Wiwynn / Facebook NVMe JBOF) / footprints 7-13 of 1140")
	)
	(layers
		(0 "F.Cu" signal "TOP")
		(4 "In1.Cu" signal "L2GND")
		(6 "In2.Cu" signal "L3")
		(8 "In3.Cu" signal "L4VCC")
		(10 "In4.Cu" signal "L5VCC")
		(12 "In5.Cu" signal "L6")
		(14 "In6.Cu" signal "L7GND")
		(2 "B.Cu" signal "BOTTOM")
		(9 "F.Adhes" user "F.Adhesive")
		(11 "B.Adhes" user "B.Adhesive")
		(13 "F.Paste" user "Package Geometry/Pastemask Top")
		(15 "B.Paste" user "Package Geometry/Pastemask Bottom")
		(5 "F.SilkS" user "Ref Des/Silkscreen Top")
		(7 "B.SilkS" user "Ref Des/Silkscreen Bottom")
		(1 "F.Mask" user "Board Geometry/Soldermask Top")
		(3 "B.Mask" user "Board Geometry/Soldermask Bottom")
		(17 "Dwgs.User" user "User.Drawings")
		(19 "Cmts.User" user "User.Comments")
		(21 "Eco1.User" user "User.Eco1")
		(23 "Eco2.User" user "User.Eco2")
		(25 "Edge.Cuts" user "Board Geometry/Outline")
		(27 "Margin" user)
		(31 "F.CrtYd" user "Package Geometry/Place Bound Top")
		(29 "B.CrtYd" user "Package Geometry/Place Bound Bottom")
		(35 "F.Fab" user "Ref Des/Assembly Top")
		(33 "B.Fab" user "Ref Des/Assembly Bottom")
	)
	(footprint ""
		(layer "F.Cu")
		(at 74.422 -444.246)
		(property "Reference" "C347"
			(at 0 0 0)
			(layer "F.SilkS")
			(hide yes)
			(effects
				(font
					(size 1.27 1.27)
				)
			)
		)
		(property "Value" "SCD1U50V3KX-GP"
			(at 0 -2.8194 0)
			(unlocked yes)
			(layer "F.Fab")
			(hide yes)
			(effects
				(font
					(size 1.016 1.016)
					(thickness 0.1524)
				)
			)
		)
		(property "Device Type" "C603H36"
			(at 0 -4.3434 0)
			(unlocked yes)
			(layer "F.Fab")
			(hide yes)
			(effects
				(font
					(size 1.016 1.016)
					(thickness 0.1524)
				)
			)
		)
		(duplicate_pad_numbers_are_jumpers no)
		(fp_line
			(start 0.508 0)
			(end -0.508 0)
			(stroke
				(width 0.2032)
				(type default)
			)
			(layer "F.SilkS")
		)
		(fp_rect
			(start -0.5842 1.3335)
			(end 0.5842 -1.3335)
			(stroke
				(width 0)
				(type default)
			)
			(fill no)
			(layer "F.CrtYd")
		)
		(fp_rect
			(start -0.5842 1.3335)
			(end 0.5842 -1.3335)
			(stroke
				(width 0)
				(type default)
			)
			(fill no)
			(layer "F.Fab")
		)
		(pad "1" smd custom
			(at 0 -0.762)
			(size 0.2159 0.2159)
			(layers "F.Cu" "F.Mask" "F.Paste")
			(net "P3V3")
			(options
				(clearance outline)
				(anchor circle)
			)
			(primitives
				(gr_poly
					(pts
						(arc
							(start -0.3302 -0.4318)
							(mid -0.402042 -0.402042)
							(end -0.4318 -0.3302)
						)
						(arc
							(start -0.4318 0.3302)
							(mid -0.402042 0.402042)
							(end -0.3302 0.4318)
						)
						(arc
							(start 0.3302 0.4318)
							(mid 0.402042 0.402042)
							(end 0.4318 0.3302)
						)
						(arc
							(start 0.4318 -0.3302)
							(mid 0.402042 -0.402042)
							(end 0.3302 -0.4318)
						)
					)
					(width 0)
					(fill yes)
				)
			)
		)
		(pad "2" smd custom
			(at 0 0.762)
			(size 0.2159 0.2159)
			(layers "F.Cu" "F.Mask" "F.Paste")
			(net "GND")
			(options
				(clearance outline)
				(anchor circle)
			)
			(primitives
				(gr_poly
					(pts
						(arc
							(start -0.3302 -0.4318)
							(mid -0.402042 -0.402042)
							(end -0.4318 -0.3302)
						)
						(arc
							(start -0.4318 0.3302)
							(mid -0.402042 0.402042)
							(end -0.3302 0.4318)
						)
						(arc
							(start 0.3302 0.4318)
							(mid 0.402042 0.402042)
							(end 0.4318 0.3302)
						)
						(arc
							(start 0.4318 -0.3302)
							(mid 0.402042 -0.402042)
							(end 0.3302 -0.4318)
						)
					)
					(width 0)
					(fill yes)
				)
			)
		)
	)
	(footprint ""
		(layer "F.Cu")
		(at 50.850292 -447.167)
		(property "Reference" "SR1132"
			(at 0 0 0)
			(layer "F.SilkS")
			(hide yes)
			(effects
				(font
					(size 1.27 1.27)
				)
			)
		)
		(property "Value" "4K7R2J-2-GP"
			(at 0.064008 -3.993896 0)
			(unlocked yes)
			(layer "F.Fab")
			(hide yes)
			(effects
				(font
					(size 1.016 1.016)
					(thickness 0.1524)
				)
			)
		)
		(property "Device Type" "R402H16"
			(at 0.064008 -5.517896 0)
			(unlocked yes)
			(layer "F.Fab")
			(hide yes)
			(effects
				(font
					(size 1.016 1.016)
					(thickness 0.1524)
				)
			)
		)
		(duplicate_pad_numbers_are_jumpers no)
		(fp_line
			(start -0.508 -0.9398)
			(end -0.508 0.9398)
			(stroke
				(width 0.1524)
				(type default)
			)
			(layer "F.SilkS")
		)
		(fp_line
			(start 0.508 -0.9398)
			(end -0.508 -0.9398)
			(stroke
				(width 0.1524)
				(type default)
			)
			(layer "F.SilkS")
		)
		(fp_rect
			(start -0.508 0.9398)
			(end 0.508 -0.9398)
			(stroke
				(width 0)
				(type default)
			)
			(fill no)
			(layer "F.CrtYd")
		)
		(fp_rect
			(start -0.508 0.9398)
			(end 0.508 -0.9398)
			(stroke
				(width 0)
				(type default)
			)
			(fill no)
			(layer "F.Fab")
		)
		(pad "1" smd custom
			(at 0 -0.4445)
			(size 0.1397 0.1397)
			(layers "F.Cu" "F.Mask" "F.Paste")
			(net "P3V3")
			(options
				(clearance outline)
				(anchor circle)
			)
			(primitives
				(gr_poly
					(pts
						(arc
							(start -0.1778 -0.2794)
							(mid -0.249642 -0.249642)
							(end -0.2794 -0.1778)
						)
						(arc
							(start -0.2794 0.1778)
							(mid -0.249642 0.249642)
							(end -0.1778 0.2794)
						)
						(arc
							(start 0.1778 0.2794)
							(mid 0.249642 0.249642)
							(end 0.2794 0.1778)
						)
						(arc
							(start 0.2794 -0.1778)
							(mid 0.249642 -0.249642)
							(end 0.1778 -0.2794)
						)
					)
					(width 0)
					(fill yes)
				)
			)
		)
		(pad "2" smd custom
			(at 0 0.4445)
			(size 0.1397 0.1397)
			(layers "F.Cu" "F.Mask" "F.Paste")
			(net "SSD_ACT_DR5")
			(options
				(clearance outline)
				(anchor circle)
			)
			(primitives
				(gr_poly
					(pts
						(arc
							(start -0.1778 -0.2794)
							(mid -0.249642 -0.249642)
							(end -0.2794 -0.1778)
						)
						(arc
							(start -0.2794 0.1778)
							(mid -0.249642 0.249642)
							(end -0.1778 0.2794)
						)
						(arc
							(start 0.1778 0.2794)
							(mid 0.249642 0.249642)
							(end 0.2794 0.1778)
						)
						(arc
							(start 0.2794 -0.1778)
							(mid 0.249642 -0.249642)
							(end 0.1778 -0.2794)
						)
					)
					(width 0)
					(fill yes)
				)
			)
		)
	)
	(footprint ""
		(layer "F.Cu")
		(at 16.637 -495.427 180)
		(property "Reference" "Q13"
			(at 0 0 180)
			(layer "F.SilkS")
			(hide yes)
			(effects
				(font
					(size 1.27 1.27)
				)
			)
		)
		(property "Value" "2N7002A-7-GP"
			(at 0.127 -8.9662 180)
			(unlocked yes)
			(layer "F.Fab")
			(hide yes)
			(effects
				(font
					(size 1.016 1.016)
					(thickness 0.1524)
				)
			)
		)
		(property "Device Type" "SOT23DGS2D4H48"
			(at 0.127 -10.4902 180)
			(unlocked yes)
			(layer "F.Fab")
			(hide yes)
			(effects
				(font
					(size 1.016 1.016)
					(thickness 0.1524)
				)
			)
		)
		(duplicate_pad_numbers_are_jumpers no)
		(fp_line
			(start 1.651 1.778)
			(end 1.651 -1.778)
			(stroke
				(width 0.1524)
				(type default)
			)
			(layer "F.SilkS")
		)
		(fp_line
			(start 1.651 -1.778)
			(end -1.651 -1.778)
			(stroke
				(width 0.1524)
				(type default)
			)
			(layer "F.SilkS")
		)
		(fp_line
			(start -1.651 1.778)
			(end 1.651 1.778)
			(stroke
				(width 0.1524)
				(type default)
			)
			(layer "F.SilkS")
		)
		(fp_line
			(start -1.651 -1.778)
			(end -1.651 1.778)
			(stroke
				(width 0.1524)
				(type default)
			)
			(layer "F.SilkS")
		)
		(fp_poly
			(pts
				(xy -1.778 1.8796) (xy -1.778 -1.8796) (xy 1.778 -1.8796) (xy 1.778 1.8796)
			)
			(stroke
				(width 0)
				(type default)
			)
			(fill no)
			(layer "F.CrtYd")
		)
		(fp_poly
			(pts
				(xy -1.778 1.8796) (xy -1.778 -1.8796) (xy 1.778 -1.8796) (xy 1.778 1.8796)
			)
			(stroke
				(width 0)
				(type default)
			)
			(fill no)
			(layer "F.Fab")
		)
		(pad "D" smd custom
			(at 0 -0.9525 180)
			(size 0.1905 0.1905)
			(layers "F.Cu" "F.Mask" "F.Paste")
			(net "SW_SSD5_R")
			(options
				(clearance outline)
				(anchor circle)
			)
			(primitives
				(gr_poly
					(pts
						(arc
							(start -0.1778 0.5715)
							(mid -0.321484 0.511984)
							(end -0.381 0.3683)
						)
						(arc
							(start -0.381 -0.3683)
							(mid -0.321484 -0.511984)
							(end -0.1778 -0.5715)
						)
						(arc
							(start 0.1778 -0.5715)
							(mid 0.321484 -0.511984)
							(end 0.381 -0.3683)
						)
						(arc
							(start 0.381 0.3683)
							(mid 0.321484 0.511984)
							(end 0.1778 0.5715)
						)
					)
					(width 0)
					(fill yes)
				)
			)
		)
		(pad "G" smd custom
			(at -0.98425 0.9525 180)
			(size 0.1905 0.1905)
			(layers "F.Cu" "F.Mask" "F.Paste")
			(net "SSD5_PWREN")
			(options
				(clearance outline)
				(anchor circle)
			)
			(primitives
				(gr_poly
					(pts
						(arc
							(start -0.1778 0.5715)
							(mid -0.321484 0.511984)
							(end -0.381 0.3683)
						)
						(arc
							(start -0.381 -0.3683)
							(mid -0.321484 -0.511984)
							(end -0.1778 -0.5715)
						)
						(arc
							(start 0.1778 -0.5715)
							(mid 0.321484 -0.511984)
							(end 0.381 -0.3683)
						)
						(arc
							(start 0.381 0.3683)
							(mid 0.321484 0.511984)
							(end 0.1778 0.5715)
						)
					)
					(width 0)
					(fill yes)
				)
			)
		)
		(pad "S" smd custom
			(at 0.98425 0.9525 180)
			(size 0.1905 0.1905)
			(layers "F.Cu" "F.Mask" "F.Paste")
			(net "GND")
			(options
				(clearance outline)
				(anchor circle)
			)
			(primitives
				(gr_poly
					(pts
						(arc
							(start -0.1778 0.5715)
							(mid -0.321484 0.511984)
							(end -0.381 0.3683)
						)
						(arc
							(start -0.381 -0.3683)
							(mid -0.321484 -0.511984)
							(end -0.1778 -0.5715)
						)
						(arc
							(start 0.1778 -0.5715)
							(mid 0.321484 -0.511984)
							(end 0.381 -0.3683)
						)
						(arc
							(start 0.381 0.3683)
							(mid 0.321484 0.511984)
							(end 0.1778 0.5715)
						)
					)
					(width 0)
					(fill yes)
				)
			)
		)
	)
	(footprint ""
		(layer "F.Cu")
		(at 252.6284 -360.5022)
		(property "Reference" "C9533"
			(at 0 0 0)
			(layer "F.SilkS")
			(hide yes)
			(effects
				(font
					(size 1.27 1.27)
				)
			)
		)
		(property "Value" "SCD01U50V2KX-1GP"
			(at 1.1811 -2.7051 0)
			(unlocked yes)
			(layer "F.Fab")
			(hide yes)
			(effects
				(font
					(size 1.016 1.016)
					(thickness 0.1524)
				)
			)
		)
		(property "Device Type" "C402H22"
			(at 1.1811 -4.2291 0)
			(unlocked yes)
			(layer "F.Fab")
			(hide yes)
			(effects
				(font
					(size 1.016 1.016)
					(thickness 0.1524)
				)
			)
		)
		(duplicate_pad_numbers_are_jumpers no)
		(fp_rect
			(start -0.4318 0.9525)
			(end 0.4318 -0.9525)
			(stroke
				(width 0)
				(type default)
			)
			(fill no)
			(layer "F.CrtYd")
		)
		(fp_rect
			(start -0.4318 0.9525)
			(end 0.4318 -0.9525)
			(stroke
				(width 0)
				(type default)
			)
			(fill no)
			(layer "F.Fab")
		)
		(pad "1" smd custom
			(at 0 -0.4445)
			(size 0.1524 0.1524)
			(layers "F.Cu" "F.Mask" "F.Paste")
			(net "P12V")
			(options
				(clearance outline)
				(anchor circle)
			)
			(primitives
				(gr_poly
					(pts
						(arc
							(start 0.3048 -0.2032)
							(mid 0.275042 -0.275042)
							(end 0.2032 -0.3048)
						)
						(arc
							(start -0.2032 -0.3048)
							(mid -0.275042 -0.275042)
							(end -0.3048 -0.2032)
						)
						(arc
							(start -0.3048 0.2032)
							(mid -0.275042 0.275042)
							(end -0.2032 0.3048)
						)
						(arc
							(start 0.2032 0.3048)
							(mid 0.275042 0.275042)
							(end 0.3048 0.2032)
						)
					)
					(width 0)
					(fill yes)
				)
			)
		)
		(pad "2" smd custom
			(at 0 0.4445)
			(size 0.1524 0.1524)
			(layers "F.Cu" "F.Mask" "F.Paste")
			(net "GND")
			(options
				(clearance outline)
				(anchor circle)
			)
			(primitives
				(gr_poly
					(pts
						(arc
							(start 0.3048 -0.2032)
							(mid 0.275042 -0.275042)
							(end 0.2032 -0.3048)
						)
						(arc
							(start -0.2032 -0.3048)
							(mid -0.275042 -0.275042)
							(end -0.3048 -0.2032)
						)
						(arc
							(start -0.3048 0.2032)
							(mid -0.275042 0.275042)
							(end -0.2032 0.3048)
						)
						(arc
							(start 0.2032 0.3048)
							(mid 0.275042 0.275042)
							(end 0.3048 0.2032)
						)
					)
					(width 0)
					(fill yes)
				)
			)
		)
	)
	(footprint ""
		(layer "F.Cu")
		(at 69.215 -440.182)
		(property "Reference" "R354"
			(at 0 0 0)
			(layer "F.SilkS")
			(hide yes)
			(effects
				(font
					(size 1.27 1.27)
				)
			)
		)
		(property "Value" "0R2J-2-GP"
			(at 0.064008 -3.993896 0)
			(unlocked yes)
			(layer "F.Fab")
			(hide yes)
			(effects
				(font
					(size 1.016 1.016)
					(thickness 0.1524)
				)
			)
		)
		(property "Device Type" "R402H16"
			(at 0.064008 -5.517896 0)
			(unlocked yes)
			(layer "F.Fab")
			(hide yes)
			(effects
				(font
					(size 1.016 1.016)
					(thickness 0.1524)
				)
			)
		)
		(duplicate_pad_numbers_are_jumpers no)
		(fp_line
			(start -0.508 -0.9398)
			(end -0.508 0.9398)
			(stroke
				(width 0.1524)
				(type default)
			)
			(layer "F.SilkS")
		)
		(fp_line
			(start 0.508 -0.9398)
			(end -0.508 -0.9398)
			(stroke
				(width 0.1524)
				(type default)
			)
			(layer "F.SilkS")
		)
		(fp_rect
			(start -0.508 0.9398)
			(end 0.508 -0.9398)
			(stroke
				(width 0)
				(type default)
			)
			(fill no)
			(layer "F.CrtYd")
		)
		(fp_rect
			(start -0.508 0.9398)
			(end 0.508 -0.9398)
			(stroke
				(width 0)
				(type default)
			)
			(fill no)
			(layer "F.Fab")
		)
		(pad "1" smd custom
			(at 0 -0.4445)
			(size 0.1397 0.1397)
			(layers "F.Cu" "F.Mask" "F.Paste")
			(net "EEPROM_SDA")
			(options
				(clearance outline)
				(anchor circle)
			)
			(primitives
				(gr_poly
					(pts
						(arc
							(start -0.1778 -0.2794)
							(mid -0.249642 -0.249642)
							(end -0.2794 -0.1778)
						)
						(arc
							(start -0.2794 0.1778)
							(mid -0.249642 0.249642)
							(end -0.1778 0.2794)
						)
						(arc
							(start 0.1778 0.2794)
							(mid 0.249642 0.249642)
							(end 0.2794 0.1778)
						)
						(arc
							(start 0.2794 -0.1778)
							(mid 0.249642 -0.249642)
							(end 0.1778 -0.2794)
						)
					)
					(width 0)
					(fill yes)
				)
			)
		)
		(pad "2" smd custom
			(at 0 0.4445)
			(size 0.1397 0.1397)
			(layers "F.Cu" "F.Mask" "F.Paste")
			(net "I2C_B_SDA")
			(options
				(clearance outline)
				(anchor circle)
			)
			(primitives
				(gr_poly
					(pts
						(arc
							(start -0.1778 -0.2794)
							(mid -0.249642 -0.249642)
							(end -0.2794 -0.1778)
						)
						(arc
							(start -0.2794 0.1778)
							(mid -0.249642 0.249642)
							(end -0.1778 0.2794)
						)
						(arc
							(start 0.1778 0.2794)
							(mid 0.249642 0.249642)
							(end 0.2794 0.1778)
						)
						(arc
							(start 0.2794 -0.1778)
							(mid 0.249642 -0.249642)
							(end 0.1778 -0.2794)
						)
					)
					(width 0)
					(fill yes)
				)
			)
		)
	)
	(footprint ""
		(layer "F.Cu")
		(at 74.4474 -352.679 180)
		(property "Reference" "R374"
			(at 0 0 180)
			(layer "F.SilkS")
			(hide yes)
			(effects
				(font
					(size 1.27 1.27)
				)
			)
		)
		(property "Value" "4K7R2J-2-GP"
			(at 0.064008 -3.993896 180)
			(unlocked yes)
			(layer "F.Fab")
			(hide yes)
			(effects
				(font
					(size 1.016 1.016)
					(thickness 0.1524)
				)
			)
		)
		(property "Device Type" "R402H16"
			(at 0.064008 -5.517896 180)
			(unlocked yes)
			(layer "F.Fab")
			(hide yes)
			(effects
				(font
					(size 1.016 1.016)
					(thickness 0.1524)
				)
			)
		)
		(duplicate_pad_numbers_are_jumpers no)
		(fp_line
			(start 0.508 -0.9398)
			(end -0.508 -0.9398)
			(stroke
				(width 0.1524)
				(type default)
			)
			(layer "F.SilkS")
		)
		(fp_line
			(start -0.508 -0.9398)
			(end -0.508 0.9398)
			(stroke
				(width 0.1524)
				(type default)
			)
			(layer "F.SilkS")
		)
		(fp_rect
			(start -0.508 0.9398)
			(end 0.508 -0.9398)
			(stroke
				(width 0)
				(type default)
			)
			(fill no)
			(layer "F.CrtYd")
		)
		(fp_rect
			(start -0.508 0.9398)
			(end 0.508 -0.9398)
			(stroke
				(width 0)
				(type default)
			)
			(fill no)
			(layer "F.Fab")
		)
		(pad "1" smd custom
			(at 0 -0.4445 180)
			(size 0.1397 0.1397)
			(layers "F.Cu" "F.Mask" "F.Paste")
			(net "P3V3")
			(options
				(clearance outline)
				(anchor circle)
			)
			(primitives
				(gr_poly
					(pts
						(arc
							(start -0.1778 -0.2794)
							(mid -0.249642 -0.249642)
							(end -0.2794 -0.1778)
						)
						(arc
							(start -0.2794 0.1778)
							(mid -0.249642 0.249642)
							(end -0.1778 0.2794)
						)
						(arc
							(start 0.1778 0.2794)
							(mid 0.249642 0.249642)
							(end 0.2794 0.1778)
						)
						(arc
							(start 0.2794 -0.1778)
							(mid 0.249642 -0.249642)
							(end 0.1778 -0.2794)
						)
					)
					(width 0)
					(fill yes)
				)
			)
		)
		(pad "2" smd custom
			(at 0 0.4445 180)
			(size 0.1397 0.1397)
			(layers "F.Cu" "F.Mask" "F.Paste")
			(net "BMC_I2C_SDA_BUF_9")
			(options
				(clearance outline)
				(anchor circle)
			)
			(primitives
				(gr_poly
					(pts
						(arc
							(start -0.1778 -0.2794)
							(mid -0.249642 -0.249642)
							(end -0.2794 -0.1778)
						)
						(arc
							(start -0.2794 0.1778)
							(mid -0.249642 0.249642)
							(end -0.1778 0.2794)
						)
						(arc
							(start 0.1778 0.2794)
							(mid 0.249642 0.249642)
							(end 0.2794 0.1778)
						)
						(arc
							(start 0.2794 -0.1778)
							(mid 0.249642 -0.249642)
							(end 0.1778 -0.2794)
						)
					)
					(width 0)
					(fill yes)
				)
			)
		)
	)
	(footprint ""
		(layer "F.Cu")
		(at 225.1075 -141.40561 90)
		(property "Reference" "R9802"
			(at 0 0 90)
			(layer "F.SilkS")
			(hide yes)
			(effects
				(font
					(size 1.27 1.27)
				)
			)
		)
		(property "Value" "0R2J-2-GP"
			(at 0.064008 -3.993896 90)
			(unlocked yes)
			(layer "F.Fab")
			(hide yes)
			(effects
				(font
					(size 1.016 1.016)
					(thickness 0.1524)
				)
			)
		)
		(property "Device Type" "R402H16"
			(at 0.064008 -5.517896 90)
			(unlocked yes)
			(layer "F.Fab")
			(hide yes)
			(effects
				(font
					(size 1.016 1.016)
					(thickness 0.1524)
				)
			)
		)
		(duplicate_pad_numbers_are_jumpers no)
		(fp_line
			(start 0.508 -0.9398)
			(end -0.508 -0.9398)
			(stroke
				(width 0.1524)
				(type default)
			)
			(layer "F.SilkS")
		)
		(fp_line
			(start -0.508 -0.9398)
			(end -0.508 0.9398)
			(stroke
				(width 0.1524)
				(type default)
			)
			(layer "F.SilkS")
		)
		(fp_rect
			(start -0.508 0.9398)
			(end 0.508 -0.9398)
			(stroke
				(width 0)
				(type default)
			)
			(fill no)
			(layer "F.CrtYd")
		)
		(fp_rect
			(start -0.508 0.9398)
			(end 0.508 -0.9398)
			(stroke
				(width 0)
				(type default)
			)
			(fill no)
			(layer "F.Fab")
		)
		(pad "1" smd custom
			(at 0 -0.4445 90)
			(size 0.1397 0.1397)
			(layers "F.Cu" "F.Mask" "F.Paste")
			(net "ATTN_LED_DR3_R")
			(options
				(clearance outline)
				(anchor circle)
			)
			(primitives
				(gr_poly
					(pts
						(arc
							(start -0.1778 -0.2794)
							(mid -0.249642 -0.249642)
							(end -0.2794 -0.1778)
						)
						(arc
							(start -0.2794 0.1778)
							(mid -0.249642 0.249642)
							(end -0.1778 0.2794)
						)
						(arc
							(start 0.1778 0.2794)
							(mid 0.249642 0.249642)
							(end 0.2794 0.1778)
						)
						(arc
							(start 0.2794 -0.1778)
							(mid 0.249642 -0.249642)
							(end 0.1778 -0.2794)
						)
					)
					(width 0)
					(fill yes)
				)
			)
		)
		(pad "2" smd custom
			(at 0 0.4445 90)
			(size 0.1397 0.1397)
			(layers "F.Cu" "F.Mask" "F.Paste")
			(net "ATTN_LED_DR3_N")
			(options
				(clearance outline)
				(anchor circle)
			)
			(primitives
				(gr_poly
					(pts
						(arc
							(start -0.1778 -0.2794)
							(mid -0.249642 -0.249642)
							(end -0.2794 -0.1778)
						)
						(arc
							(start -0.2794 0.1778)
							(mid -0.249642 0.249642)
							(end -0.1778 0.2794)
						)
						(arc
							(start 0.1778 0.2794)
							(mid 0.249642 0.249642)
							(end 0.2794 0.1778)
						)
						(arc
							(start 0.2794 -0.1778)
							(mid 0.249642 -0.249642)
							(end 0.1778 -0.2794)
						)
					)
					(width 0)
					(fill yes)
				)
			)
		)
	)
)
